(kicad_pcb
	(version 20211014)
	(generator pcbnew)
	(general
    (thickness 1.6)
  )
	(paper "A4")
	(title_block
    (title "SA800U (Snapdragon 845) Baseboard")
    (date "2023-10-19")
    (rev "1.0.3")
    (company "Antmicro Ltd.")
    (comment 1 "www.antmicro.com")
		(comment 9 "footprints 446-455 of 589")
	)
	(layers
    (0 "F.Cu" signal)
    (1 "In1.Cu" power)
    (2 "In2.Cu" signal)
    (3 "In3.Cu" signal)
    (4 "In4.Cu" power)
    (31 "B.Cu" signal)
    (32 "B.Adhes" user "B.Adhesive")
    (33 "F.Adhes" user "F.Adhesive")
    (34 "B.Paste" user)
    (35 "F.Paste" user)
    (36 "B.SilkS" user "B.Silkscreen")
    (37 "F.SilkS" user "F.Silkscreen")
    (38 "B.Mask" user)
    (39 "F.Mask" user)
    (40 "Dwgs.User" user "User.Drawings")
    (41 "Cmts.User" user "User.Comments")
    (42 "Eco1.User" user "User.Eco1")
    (43 "Eco2.User" user "User.Eco2")
    (44 "Edge.Cuts" user)
    (45 "Margin" user)
    (46 "B.CrtYd" user "B.Courtyard")
    (47 "F.CrtYd" user "F.Courtyard")
    (48 "B.Fab" user)
    (49 "F.Fab" user)
  )
	(footprint "sa800u-baseboard-hw-footprints:TP_SMD_0.75mm" (layer "B.Cu")
    (tedit 5E4A9375)
    (at 107.1 135.9 -90)
    (property "Author" "Antmicro")
    (property "License" "Apache-2.0")
    (property "MPN" "")
    (property "Manufacturer" "")
    (property "Sheetfile" "usb-c-interface.kicad_sch")
    (property "Sheetname" "USB-C Interface ")
    (attr smd)
    (fp_text reference "TP106" (at -3.71 -0.37 90) (layer "B.SilkS")
      (effects (font (size 0.7 0.7) (thickness 0.15)) (justify left bottom mirror))
    )
    (fp_text value "TP_0.75mm_SMD" (at 0 -1.2 90) (layer "B.Fab")
      (effects (font (size 0.7 0.7) (thickness 0.15)) (justify left bottom mirror))
    )
    (fp_text user "Author: Antmicro" (at -0.4 -3.901 90) (layer "B.Fab") hide
      (effects (font (size 0.7 0.7) (thickness 0.15)) (justify left bottom mirror))
    )
    (fp_text user "License: Apache-2.0" (at -0.4 -5.101 90) (layer "B.Fab") hide
      (effects (font (size 0.7 0.7) (thickness 0.15)) (justify left bottom mirror))
    )
    (fp_text user "${REFERENCE}" (at -0.4 -2.7 90) (layer "B.Fab") hide
      (effects (font (size 0.7 0.7) (thickness 0.15)) (justify left bottom mirror))
    )
    (pad "1" smd circle (at 0 0 270) (size 0.75 0.75) (layers "B.Cu" "B.Mask")
      (net 100 "USB2_FAULT") (pinfunction "1") (pintype "passive"))
  )
	(footprint "sa800u-baseboard-hw-footprints:TP_SMD_0.75mm" (layer "B.Cu")
    (tedit 5E4A9375)
    (at 109.5 135.9 -90)
    (property "Author" "Antmicro")
    (property "License" "Apache-2.0")
    (property "MPN" "")
    (property "Manufacturer" "")
    (property "Sheetfile" "usb-c-interface.kicad_sch")
    (property "Sheetname" "USB-C Interface ")
    (attr smd)
    (fp_text reference "TP107" (at -3.71 -0.37 90) (layer "B.SilkS")
      (effects (font (size 0.7 0.7) (thickness 0.15)) (justify left bottom mirror))
    )
    (fp_text value "TP_0.75mm_SMD" (at 0 -1.2 90) (layer "B.Fab")
      (effects (font (size 0.7 0.7) (thickness 0.15)) (justify left bottom mirror))
    )
    (fp_text user "Author: Antmicro" (at -0.4 -3.901 90) (layer "B.Fab") hide
      (effects (font (size 0.7 0.7) (thickness 0.15)) (justify left bottom mirror))
    )
    (fp_text user "${REFERENCE}" (at -0.4 -2.7 90) (layer "B.Fab") hide
      (effects (font (size 0.7 0.7) (thickness 0.15)) (justify left bottom mirror))
    )
    (fp_text user "License: Apache-2.0" (at -0.4 -5.101 90) (layer "B.Fab") hide
      (effects (font (size 0.7 0.7) (thickness 0.15)) (justify left bottom mirror))
    )
    (pad "1" smd circle (at 0 0 270) (size 0.75 0.75) (layers "B.Cu" "B.Mask")
      (net 101 "USB2_EN") (pinfunction "1") (pintype "passive"))
  )
	(footprint "sa800u-baseboard-hw-footprints:TP_SMD_0.75mm" (layer "B.Cu")
    (tedit 5E4A9375)
    (at 110 147.6 90)
    (property "Author" "Antmicro")
    (property "License" "Apache-2.0")
    (property "MPN" "")
    (property "Manufacturer" "")
    (property "Sheetfile" "usb-c-interface.kicad_sch")
    (property "Sheetname" "USB-C Interface ")
    (attr smd)
    (fp_text reference "TP108" (at -0.33 -0.3 270) (layer "B.SilkS")
      (effects (font (size 0.7 0.7) (thickness 0.15)) (justify left bottom mirror))
    )
    (fp_text value "TP_0.75mm_SMD" (at 0 -1.2 270) (layer "B.Fab")
      (effects (font (size 0.7 0.7) (thickness 0.15)) (justify left bottom mirror))
    )
    (fp_text user "License: Apache-2.0" (at -0.4 -5.101 270) (layer "B.Fab") hide
      (effects (font (size 0.7 0.7) (thickness 0.15)) (justify left bottom mirror))
    )
    (fp_text user "Author: Antmicro" (at -0.4 -3.901 270) (layer "B.Fab") hide
      (effects (font (size 0.7 0.7) (thickness 0.15)) (justify left bottom mirror))
    )
    (fp_text user "${REFERENCE}" (at -0.4 -2.7 270) (layer "B.Fab") hide
      (effects (font (size 0.7 0.7) (thickness 0.15)) (justify left bottom mirror))
    )
    (pad "1" smd circle (at 0 0 90) (size 0.75 0.75) (layers "B.Cu" "B.Mask")
      (net 292 "/USB-C Interface /USB2_FAULT_5V") (pinfunction "1") (pintype "passive"))
  )
	(footprint "sa800u-baseboard-hw-footprints:TP_SMD_0.75mm" (layer "B.Cu")
    (tedit 5E4A9375)
    (at 111.2 147.6 90)
    (property "Author" "Antmicro")
    (property "License" "Apache-2.0")
    (property "MPN" "")
    (property "Manufacturer" "")
    (property "Sheetfile" "usb-c-interface.kicad_sch")
    (property "Sheetname" "USB-C Interface ")
    (attr smd)
    (fp_text reference "TP109" (at -0.32 -0.6 270) (layer "B.SilkS")
      (effects (font (size 0.7 0.7) (thickness 0.15)) (justify left bottom mirror))
    )
    (fp_text value "TP_0.75mm_SMD" (at 0 -1.2 270) (layer "B.Fab")
      (effects (font (size 0.7 0.7) (thickness 0.15)) (justify left bottom mirror))
    )
    (fp_text user "Author: Antmicro" (at -0.4 -3.901 270) (layer "B.Fab") hide
      (effects (font (size 0.7 0.7) (thickness 0.15)) (justify left bottom mirror))
    )
    (fp_text user "License: Apache-2.0" (at -0.4 -5.101 270) (layer "B.Fab") hide
      (effects (font (size 0.7 0.7) (thickness 0.15)) (justify left bottom mirror))
    )
    (fp_text user "${REFERENCE}" (at -0.4 -2.7 270) (layer "B.Fab") hide
      (effects (font (size 0.7 0.7) (thickness 0.15)) (justify left bottom mirror))
    )
    (pad "1" smd circle (at 0 0 90) (size 0.75 0.75) (layers "B.Cu" "B.Mask")
      (net 291 "/USB-C Interface /USB2_SINK_5V") (pinfunction "1") (pintype "passive"))
  )
	(footprint "sa800u-baseboard-hw-footprints:TP_SMD_0.75mm" (layer "B.Cu")
    (tedit 5E4A9375)
    (at 112 142.5492)
    (property "Author" "Antmicro")
    (property "License" "Apache-2.0")
    (property "MPN" "")
    (property "Manufacturer" "")
    (property "Sheetfile" "usb-c-interface.kicad_sch")
    (property "Sheetname" "USB-C Interface ")
    (attr smd)
    (fp_text reference "TP110" (at 3.72 0.4308 180) (layer "B.SilkS")
      (effects (font (size 0.7 0.7) (thickness 0.15)) (justify left bottom mirror))
    )
    (fp_text value "TP_0.75mm_SMD" (at 0 -1.2 180) (layer "B.Fab")
      (effects (font (size 0.7 0.7) (thickness 0.15)) (justify left bottom mirror))
    )
    (fp_text user "License: Apache-2.0" (at -0.4 -5.101 180) (layer "B.Fab") hide
      (effects (font (size 0.7 0.7) (thickness 0.15)) (justify left bottom mirror))
    )
    (fp_text user "${REFERENCE}" (at -0.4 -2.7 180) (layer "B.Fab") hide
      (effects (font (size 0.7 0.7) (thickness 0.15)) (justify left bottom mirror))
    )
    (fp_text user "Author: Antmicro" (at -0.4 -3.901 180) (layer "B.Fab") hide
      (effects (font (size 0.7 0.7) (thickness 0.15)) (justify left bottom mirror))
    )
    (pad "1" smd circle (at 0 0) (size 0.75 0.75) (layers "B.Cu" "B.Mask")
      (net 290 "/USB-C Interface /USB2_CC_SELECT") (pinfunction "1") (pintype "passive"))
  )
	(footprint "sa800u-baseboard-hw-footprints:TP_SMD_0.75mm" (layer "B.Cu")
    (tedit 5E4A9375)
    (at 123.8 140.5492)
    (property "Author" "Antmicro")
    (property "License" "Apache-2.0")
    (property "MPN" "")
    (property "Manufacturer" "")
    (property "Sheetfile" "usb-c-interface.kicad_sch")
    (property "Sheetname" "USB-C Interface ")
    (attr smd)
    (fp_text reference "TP111" (at 1.21 -0.4392 180) (layer "B.SilkS")
      (effects (font (size 0.7 0.7) (thickness 0.15)) (justify left bottom mirror))
    )
    (fp_text value "TP_0.75mm_SMD" (at 0 -1.2 180) (layer "B.Fab")
      (effects (font (size 0.7 0.7) (thickness 0.15)) (justify left bottom mirror))
    )
    (fp_text user "License: Apache-2.0" (at -0.4 -5.101 180) (layer "B.Fab") hide
      (effects (font (size 0.7 0.7) (thickness 0.15)) (justify left bottom mirror))
    )
    (fp_text user "Author: Antmicro" (at -0.4 -3.901 180) (layer "B.Fab") hide
      (effects (font (size 0.7 0.7) (thickness 0.15)) (justify left bottom mirror))
    )
    (fp_text user "${REFERENCE}" (at -0.4 -2.7 180) (layer "B.Fab") hide
      (effects (font (size 0.7 0.7) (thickness 0.15)) (justify left bottom mirror))
    )
    (pad "1" smd circle (at 0 0) (size 0.75 0.75) (layers "B.Cu" "B.Mask")
      (net 228 "/USB-C Interface /5V0_DBG") (pinfunction "1") (pintype "passive"))
  )
	(footprint "sa800u-baseboard-hw-footprints:R_0402_1005Metric" (layer "B.Cu")
    (tedit 5FD9C158)
    (at 61.9 113.8 180)
    (descr "Resistor SMD 0402")
    (tags "resistor SMD 0402")
    (property "Author" "Antmicro")
    (property "License" "Apache-2.0")
    (property "MPN" "CR0402-FX-2492GLF")
    (property "Manufacturer" "Bourns")
    (property "Sheetfile" "poe.kicad_sch")
    (property "Sheetname" "PoE")
    (property "Tolerance" "1%")
    (property "Val" "24k9")
    (attr smd)
    (fp_text reference "R143" (at -3.76 -0.3) (layer "B.SilkS")
      (effects (font (size 0.7 0.7) (thickness 0.15)) (justify left bottom mirror))
    )
    (fp_text value "R_24k9_0402" (at 0 -1.4) (layer "B.Fab")
      (effects (font (size 0.7 0.7) (thickness 0.15)) (justify left bottom mirror))
    )
    (fp_text user "License: Apache-2.0" (at -0.95 -5.169) (layer "B.Fab") hide
      (effects (font (size 0.7 0.7) (thickness 0.15)) (justify left bottom mirror))
    )
    (fp_text user "${REFERENCE}" (at -0.95 -3.168) (layer "B.Fab") hide
      (effects (font (size 0.7 0.7) (thickness 0.15)) (justify left bottom mirror))
    )
    (fp_text user "Author: Antmicro" (at -0.95 -4.169) (layer "B.Fab") hide
      (effects (font (size 0.7 0.7) (thickness 0.15)) (justify left bottom mirror))
    )
    (fp_rect (start -0.93 0.47) (end 0.93 -0.47) (layer "B.CrtYd") (width 0.05) (fill none))
    (fp_rect (start -0.5 0.25) (end 0.5 -0.25) (layer "B.Fab") (width 0.15) (fill none))
    (pad "1" smd roundrect (at -0.485 0 180) (size 0.59 0.64) (layers "B.Cu" "B.Paste" "B.Mask") (roundrect_rratio 0.25)
      (net 73 "/PoE/VDD_POE") (pintype "passive"))
    (pad "2" smd roundrect (at 0.485 0 180) (size 0.59 0.64) (layers "B.Cu" "B.Paste" "B.Mask") (roundrect_rratio 0.25)
      (net 145 "/PoE/DEN") (pintype "passive"))
  )
	(footprint "sa800u-baseboard-hw-footprints:SOIC-8-1EP_3.9x4.9x1.75mm_P1.27mm" (layer "B.Cu")
    (tedit 5FD9C0CC)
    (at 60.7 109.5 90)
    (tags "Integrated Circuit")
    (property "Arrow Part Number" "TPS2378DDA")
    (property "Arrow Price/Stock" "https://www.arrow.com/en/products/tps2378dda/texas-instruments")
    (property "Author" "Antmicro")
    (property "Description" "IEEE 802.3at PoE High-Power PD Interface with AUX Control")
    (property "License" "Apache-2.0")
    (property "MPN" "TPS2378DDA")
    (property "Manufacturer" "Texas Instruments")
    (property "Mouser Part Number" "595-TPS2378DDA")
    (property "Mouser Price/Stock" "https://www.mouser.co.uk/ProductDetail/Texas-Instruments/TPS2378DDA?qs=5771e39Rz9HhOSwUvwIrNw%3D%3D")
    (property "Sheetfile" "poe.kicad_sch")
    (property "Sheetname" "PoE")
    (attr smd)
    (fp_text reference "IC2" (at 0.86 3.65 270) (layer "B.SilkS")
      (effects (font (size 0.7 0.7) (thickness 0.15)) (justify left bottom mirror))
    )
    (fp_text value "TPS2378DDA" (at 0 -3.65 270) (layer "B.Fab")
      (effects (font (size 0.7 0.7) (thickness 0.15)) (justify left bottom mirror))
    )
    (fp_text user "License: Apache-2.0" (at -3.476 -5.099 270) (layer "B.Fab") hide
      (effects (font (size 0.7 0.7) (thickness 0.15)) (justify left bottom mirror))
    )
    (fp_text user "Author: Antmicro" (at -3.476 -6.099 270) (layer "B.Fab") hide
      (effects (font (size 0.7 0.7) (thickness 0.15)) (justify left bottom mirror))
    )
    (fp_text user "${REFERENCE}" (at -3.476 -7.099 270) (layer "B.Fab") hide
      (effects (font (size 0.7 0.7) (thickness 0.15)) (justify left bottom mirror))
    )
    (fp_line (start 1.95 2.55) (end -1.95 2.55) (layer "B.SilkS") (width 0.15))
    (fp_line (start 1.95 -2.55) (end -1.95 -2.55) (layer "B.SilkS") (width 0.15))
    (fp_circle (center -2.5 2.45) (end -2.45 2.4) (layer "B.SilkS") (width 0.15) (fill solid))
    (fp_rect (start -3.55 2.7) (end 3.55 -2.7) (layer "B.CrtYd") (width 0.05) (fill none))
    (fp_line (start -0.683 2.452) (end 1.949 2.452) (layer "B.Fab") (width 0.15))
    (fp_line (start -1.95 1.18) (end -0.683 2.452) (layer "B.Fab") (width 0.15))
    (fp_line (start -1.95 -2.45) (end -1.95 1.18) (layer "B.Fab") (width 0.15))
    (fp_line (start 1.949 -2.45) (end -1.95 -2.45) (layer "B.Fab") (width 0.15))
    (fp_line (start 1.949 2.452) (end 1.949 -2.45) (layer "B.Fab") (width 0.15))
    (pad "1" smd roundrect (at -2.714 1.905) (size 0.65 1.525) (layers "B.Cu" "B.Paste" "B.Mask") (roundrect_rratio 0.25)
      (net 73 "/PoE/VDD_POE") (pinfunction "VDD") (pintype "power_in"))
    (pad "2" smd roundrect (at -2.714 0.635) (size 0.65 1.525) (layers "B.Cu" "B.Paste" "B.Mask") (roundrect_rratio 0.25)
      (net 145 "/PoE/DEN") (pinfunction "DEN") (pintype "passive"))
    (pad "3" smd roundrect (at -2.714 -0.632) (size 0.65 1.525) (layers "B.Cu" "B.Paste" "B.Mask") (roundrect_rratio 0.25)
      (net 146 "/PoE/CLS") (pinfunction "CLS") (pintype "passive"))
    (pad "4" smd roundrect (at -2.714 -1.902) (size 0.65 1.525) (layers "B.Cu" "B.Paste" "B.Mask") (roundrect_rratio 0.25)
      (net 135 "/PoE/VSS_POE") (pinfunction "VSS") (pintype "power_in"))
    (pad "5" smd roundrect (at 2.712 -1.902) (size 0.65 1.525) (layers "B.Cu" "B.Paste" "B.Mask") (roundrect_rratio 0.25)
      (net 7 "GNDD") (pinfunction "RTN") (pintype "passive"))
    (pad "6" smd roundrect (at 2.712 -0.632) (size 0.65 1.525) (layers "B.Cu" "B.Paste" "B.Mask") (roundrect_rratio 0.25)
      (net 147 "/PoE/CDB") (pinfunction "CDB") (pintype "passive"))
    (pad "7" smd roundrect (at 2.712 0.635) (size 0.65 1.525) (layers "B.Cu" "B.Paste" "B.Mask") (roundrect_rratio 0.25)
      (net 384 "Net-(IC2-Pad7)") (pinfunction "T2P") (pintype "passive"))
    (pad "8" smd roundrect (at 2.712 1.905) (size 0.65 1.525) (layers "B.Cu" "B.Paste" "B.Mask") (roundrect_rratio 0.25)
      (net 174 "/PoE/APD") (pinfunction "APD") (pintype "passive"))
    (pad "9" smd roundrect (at 0 0 90) (size 2.29 3.1) (layers "B.Cu" "B.Paste" "B.Mask") (roundrect_rratio 0.05)
      (net 135 "/PoE/VSS_POE") (pinfunction "EP") (pintype "power_in"))
  )
	(footprint "sa800u-baseboard-hw-footprints:TP_SMD_0.75mm" (layer "B.Cu")
    (tedit 5E4A9375)
    (at 126.5 130.6 180)
    (property "Author" "Antmicro")
    (property "License" "Apache-2.0")
    (property "MPN" "")
    (property "Manufacturer" "")
    (property "Sheetfile" "usb-c-interface.kicad_sch")
    (property "Sheetname" "USB-C Interface ")
    (attr smd)
    (fp_text reference "TP100" (at -3.74 -0.32) (layer "B.SilkS")
      (effects (font (size 0.7 0.7) (thickness 0.15)) (justify left bottom mirror))
    )
    (fp_text value "TP_0.75mm_SMD" (at 0 -1.2) (layer "B.Fab")
      (effects (font (size 0.7 0.7) (thickness 0.15)) (justify left bottom mirror))
    )
    (fp_text user "Author: Antmicro" (at -0.4 -3.901) (layer "B.Fab") hide
      (effects (font (size 0.7 0.7) (thickness 0.15)) (justify left bottom mirror))
    )
    (fp_text user "${REFERENCE}" (at -0.4 -2.7) (layer "B.Fab") hide
      (effects (font (size 0.7 0.7) (thickness 0.15)) (justify left bottom mirror))
    )
    (fp_text user "License: Apache-2.0" (at -0.4 -5.101) (layer "B.Fab") hide
      (effects (font (size 0.7 0.7) (thickness 0.15)) (justify left bottom mirror))
    )
    (pad "1" smd circle (at 0 0 180) (size 0.75 0.75) (layers "B.Cu" "B.Mask")
      (net 129 "DBG_RXD") (pinfunction "1") (pintype "passive"))
  )
	(footprint "sa800u-baseboard-hw-footprints:SOT-23-3" (layer "B.Cu")
    (tedit 5D5D4314)
    (at 79.8 147.1 180)
    (property "Author" "Antmicro")
    (property "License" "Apache-2.0")
    (property "MPN" "BSS84")
    (property "Manufacturer" "ON Semiconductor")
    (property "Sheetfile" "psu.kicad_sch")
    (property "Sheetname" "PSU")
    (attr smd)
    (fp_text reference "Q8" (at -0.86 1.8) (layer "B.SilkS")
      (effects (font (size 0.7 0.7) (thickness 0.15)) (justify left bottom mirror))
    )
    (fp_text value "BSS84" (at -1.9 -2.7) (layer "B.Fab")
      (effects (font (size 0.7 0.7) (thickness 0.15)) (justify left bottom mirror))
    )
    (fp_text user "${REFERENCE}" (at -1.837 -4) (layer "B.Fab") hide
      (effects (font (size 0.7 0.7) (thickness 0.15)) (justify left bottom mirror))
    )
    (fp_text user "License: Apache-2.0" (at -1.8 -6.8) (layer "B.Fab") hide
      (effects (font (size 0.7 0.7) (thickness 0.15)) (justify left bottom mirror))
    )
    (fp_text user "Author: Antmicro" (at -1.837 -5.3) (layer "B.Fab") hide
      (effects (font (size 0.7 0.7) (thickness 0.15)) (justify left bottom mirror))
    )
    (fp_line (start 0.7 0.4) (end 0.7 1.5) (layer "B.SilkS") (width 0.15))
    (fp_line (start -0.7 -1.5) (end -0.7 -1.35) (layer "B.SilkS") (width 0.15))
    (fp_line (start 0.7 1.5) (end -0.7 1.5) (layer "B.SilkS") (width 0.15))
    (fp_line (start -1.45 1.35) (end -0.85 1.35) (layer "B.SilkS") (width 0.15))
    (fp_line (start -0.85 1.35) (end -0.7 1.5) (layer "B.SilkS") (width 0.15))
    (fp_line (start 0.7 -0.4) (end 0.7 -1.5) (layer "B.SilkS") (width 0.15))
    (fp_line (start 0.7 -1.5) (end -0.7 -1.5) (layer "B.SilkS") (width 0.15))
    (fp_line (start 0.825 0.45) (end 1.75 0.45) (layer "B.CrtYd") (width 0.05))
    (fp_line (start -0.9 1.4) (end -1.75 1.4) (layer "B.CrtYd") (width 0.05))
    (fp_line (start -1.75 0.5) (end -1.75 1.4) (layer "B.CrtYd") (width 0.05))
    (fp_line (start -0.85 0.5) (end -1.75 0.5) (layer "B.CrtYd") (width 0.05))
    (fp_line (start -0.9 1.6) (end -0.9 1.4) (layer "B.CrtYd") (width 0.05))
    (fp_line (start -1.75 -0.5) (end -0.85 -0.5) (layer "B.CrtYd") (width 0.05))
    (fp_line (start -0.85 -1.65) (end -0.85 -1.4) (layer "B.CrtYd") (width 0.05))
    (fp_line (start 0.825 1.6) (end 0.825 0.45) (layer "B.CrtYd") (width 0.05))
    (fp_line (start 1.75 0.45) (end 1.75 -0.45) (layer "B.CrtYd") (width 0.05))
    (fp_line (start 0.85 -0.45) (end 0.85 -1.65) (layer "B.CrtYd") (width 0.05))
    (fp_line (start -1.75 -1.4) (end -1.75 -0.5) (layer "B.CrtYd") (width 0.05))
    (fp_line (start -0.85 -0.5) (end -0.85 0.5) (layer "B.CrtYd") (width 0.05))
    (fp_line (start 1.75 -0.45) (end 0.85 -0.45) (layer "B.CrtYd") (width 0.05))
    (fp_line (start 0.85 -1.65) (end -0.85 -1.65) (layer "B.CrtYd") (width 0.05))
    (fp_line (start -0.9 1.6) (end 0.825 1.6) (layer "B.CrtYd") (width 0.05))
    (fp_line (start -0.85 -1.4) (end -1.75 -1.4) (layer "B.CrtYd") (width 0.05))
    (fp_line (start -0.437 1.526) (end -0.712 1.325) (layer "B.Fab") (width 0.15))
    (fp_line (start -0.437 1.526) (end 0.688 1.526) (layer "B.Fab") (width 0.15))
    (fp_line (start -0.712 1.325) (end -0.712 -1.523) (layer "B.Fab") (width 0.15))
    (fp_line (start -0.712 -1.519) (end 0.688 -1.519) (layer "B.Fab") (width 0.15))
    (fp_line (start 0.688 -1.519) (end 0.688 1.52) (layer "B.Fab") (width 0.15))
    (pad "1" smd roundrect (at -1.1 0.951 180) (size 1 0.6) (layers "B.Cu" "B.Paste" "B.Mask") (roundrect_rratio 0.15)
      (net 339 "/PSU/AUX_VALID") (pinfunction "G") (pintype "bidirectional"))
    (pad "2" smd roundrect (at -1.1 -0.949 180) (size 1 0.6) (layers "B.Cu" "B.Paste" "B.Mask") (roundrect_rratio 0.15)
      (net 1 "GND") (pinfunction "D") (pintype "bidirectional"))
    (pad "3" smd roundrect (at 1.1 0.0005 180) (size 1 0.6) (layers "B.Cu" "B.Paste" "B.Mask") (roundrect_rratio 0.15)
      (net 388 "Net-(Q8-Pad3)") (pinfunction "S") (pintype "bidirectional"))
  )
)
